(kicad_pcb
	(version 20260206)
	(generator "pcbnew")
	(generator_version "10.0")
	(general
		(thickness 1.6)
		(legacy_teardrops no)
	)
	(paper "A4")
	(title_block
		(title "netronome-mezz — pcbd0082-001_rev01_jul9_a.brd")
		(comment 1 "Open CloudServer (Microsoft) / footprints 551-559 of 714")
	)
	(layers
		(0 "F.Cu" signal "TOP")
		(4 "In1.Cu" signal "02_GND")
		(6 "In2.Cu" signal "03_SIG")
		(8 "In3.Cu" signal "04_SIG")
		(10 "In4.Cu" signal "05_GND")
		(12 "In5.Cu" signal "06_PWR1")
		(14 "In6.Cu" signal "07_SIG")
		(16 "In7.Cu" signal "08_SIG")
		(18 "In8.Cu" signal "09_GND")
		(2 "B.Cu" signal "BOTTOM")
		(9 "F.Adhes" user "F.Adhesive")
		(11 "B.Adhes" user "B.Adhesive")
		(13 "F.Paste" user "Package Geometry/Pastemask Top")
		(15 "B.Paste" user "Package Geometry/Pastemask Bottom")
		(5 "F.SilkS" user "Ref Des/Silkscreen Top")
		(7 "B.SilkS" user "Ref Des/Silkscreen Bottom")
		(1 "F.Mask" user "Board Geometry/Soldermask Top")
		(3 "B.Mask" user "Board Geometry/Soldermask Bottom")
		(17 "Dwgs.User" user "User.Drawings")
		(19 "Cmts.User" user "User.Comments")
		(21 "Eco1.User" user "User.Eco1")
		(23 "Eco2.User" user "User.Eco2")
		(25 "Edge.Cuts" user "Board Geometry/Outline")
		(27 "Margin" user)
		(31 "F.CrtYd" user "Package Geometry/Place Bound Top")
		(29 "B.CrtYd" user "Package Geometry/Place Bound Bottom")
		(35 "F.Fab" user "Ref Des/Assembly Top")
		(33 "B.Fab" user "Ref Des/Assembly Bottom")
		(45 "User.4" user "COMPVAL_TYPE_BOTTOM")
	)
	(footprint ""
		(layer "B.Cu")
		(at 28.194 24.003 90)
		(property "Reference" "R58"
			(at -0.40767 3.175 0)
			(unlocked yes)
			(layer "B.SilkS")
			(effects
				(font
					(size 0.7874 0.5842)
					(thickness 0.127)
				)
				(justify left mirror)
			)
		)
		(property "Value" "4.75K"
			(at 0.148158 1.3462 0)
			(unlocked yes)
			(layer "B.Fab")
			(hide yes)
			(effects
				(font
					(size 1.27 0.9652)
					(thickness 0.000001)
				)
				(justify left mirror)
			)
		)
		(property "Device Type" "REST4024"
			(at 0.148158 1.3462 0)
			(unlocked yes)
			(layer "B.Fab")
			(hide yes)
			(effects
				(font
					(size 1.27 0.9652)
					(thickness 0.000001)
				)
				(justify left mirror)
			)
		)
		(duplicate_pad_numbers_are_jumpers no)
		(fp_poly
			(pts
				(xy -0.635 1.0668) (xy -0.635 -1.0668) (xy 0.635 -1.0668) (xy 0.635 1.0668)
			)
			(stroke
				(width 0)
				(type default)
			)
			(fill no)
			(layer "B.CrtYd")
		)
		(fp_line
			(start 0.254 -0.508)
			(end -0.254 -0.508)
			(stroke
				(width 0.0254)
				(type default)
			)
			(layer "B.Fab")
		)
		(fp_line
			(start -0.254 -0.508)
			(end -0.254 0.508)
			(stroke
				(width 0.0254)
				(type default)
			)
			(layer "B.Fab")
		)
		(fp_line
			(start 0.254 0.508)
			(end 0.254 -0.508)
			(stroke
				(width 0.0254)
				(type default)
			)
			(layer "B.Fab")
		)
		(fp_line
			(start -0.254 0.508)
			(end 0.254 0.508)
			(stroke
				(width 0.0254)
				(type default)
			)
			(layer "B.Fab")
		)
		(pad "1" smd rect
			(at 0 -0.4191 270)
			(size 0.508 0.5334)
			(layers "B.Cu" "B.Mask" "B.Paste")
			(net "NFP_CPLD_INT_L")
		)
		(pad "2" smd rect
			(at 0 0.4191 270)
			(size 0.508 0.5334)
			(layers "B.Cu" "B.Mask" "B.Paste")
			(net "GND")
		)
		(zone
			(layer "B.Cu")
			(hatch none 0.5)
			(connect_pads
				(clearance 0)
			)
			(min_thickness 0.25)
			(keepout
				(tracks not_allowed)
				(vias allowed)
				(pads allowed)
				(copperpour not_allowed)
				(footprints allowed)
			)
			(placement
				(enabled no)
				(sheetname "")
			)
			(fill
				(thermal_gap 0.5)
				(thermal_bridge_width 0.5)
				(island_removal_mode 0)
			)
			(polygon
				(pts
					(xy 28.1686 24.0284) (xy 28.2194 24.0284) (xy 28.2194 23.9776) (xy 28.1686 23.9776)
				)
			)
		)
	)
	(footprint ""
		(layer "B.Cu")
		(at 60.236989 27.541982)
		(property "Reference" "C177"
			(at 1.458341 0.906018 270)
			(unlocked yes)
			(layer "B.SilkS")
			(effects
				(font
					(size 0.7874 0.5842)
					(thickness 0.127)
				)
				(justify mirror)
			)
		)
		(property "Value" ""
			(at 0 0 0)
			(layer "B.Fab")
			(effects
				(font
					(size 1.27 1.27)
				)
				(justify mirror)
			)
		)
		(duplicate_pad_numbers_are_jumpers no)
		(fp_circle
			(center 0 0)
			(end 0.104648 0)
			(stroke
				(width 0.1016)
				(type default)
			)
			(fill no)
			(layer "B.SilkS")
		)
		(fp_poly
			(pts
				(xy 0.381 -0.889) (xy 0.381 0.889) (xy -0.381 0.889) (xy -0.381 -0.889)
			)
			(stroke
				(width 0)
				(type default)
			)
			(fill no)
			(layer "B.CrtYd")
		)
		(fp_line
			(start -0.508 -1.016)
			(end -0.508 1.016)
			(stroke
				(width 0.0254)
				(type default)
			)
			(layer "B.Fab")
		)
		(fp_line
			(start -0.508 1.016)
			(end 0.508 1.016)
			(stroke
				(width 0.0254)
				(type default)
			)
			(layer "B.Fab")
		)
		(fp_line
			(start 0.254 -1.016)
			(end -0.508 -1.016)
			(stroke
				(width 0.0254)
				(type default)
			)
			(layer "B.Fab")
		)
		(fp_line
			(start 0.508 -1.016)
			(end 0.254 -1.016)
			(stroke
				(width 0.0254)
				(type default)
			)
			(layer "B.Fab")
		)
		(fp_line
			(start 0.508 1.016)
			(end 0.508 -1.016)
			(stroke
				(width 0.0254)
				(type default)
			)
			(layer "B.Fab")
		)
		(pad "1" smd custom
			(at 0 -0.500126 180)
			(size 0.127 0.127)
			(layers "B.Cu" "B.Mask" "B.Paste")
			(net "VDD_CORE")
			(options
				(clearance outline)
				(anchor circle)
			)
			(primitives
				(gr_poly
					(pts
						(xy -0.1778 0.254) (xy 0.1778 0.254) (xy 0.254 0.1778) (xy 0.254 -0.1778) (xy 0.1778 -0.254) (xy -0.1778 -0.254)
						(xy -0.254 -0.1778) (xy -0.254 0.1778)
					)
					(width 0)
					(fill yes)
				)
			)
		)
		(pad "2" smd custom
			(at 0 0.500126 180)
			(size 0.127 0.127)
			(layers "B.Cu" "B.Mask" "B.Paste")
			(net "GND")
			(options
				(clearance outline)
				(anchor circle)
			)
			(primitives
				(gr_poly
					(pts
						(xy -0.1778 0.254) (xy 0.1778 0.254) (xy 0.254 0.1778) (xy 0.254 -0.1778) (xy 0.1778 -0.254) (xy -0.1778 -0.254)
						(xy -0.254 -0.1778) (xy -0.254 0.1778)
					)
					(width 0)
					(fill yes)
				)
			)
		)
	)
	(footprint ""
		(layer "B.Cu")
		(at 82.931 41.5798)
		(property "Reference" "R4"
			(at 0.86233 0.9652 270)
			(unlocked yes)
			(layer "B.SilkS")
			(effects
				(font
					(size 0.7874 0.5842)
					(thickness 0.127)
				)
				(justify left mirror)
			)
		)
		(property "Value" "30.1K"
			(at 0.148158 1.3462 270)
			(unlocked yes)
			(layer "B.Fab")
			(hide yes)
			(effects
				(font
					(size 1.27 0.9652)
					(thickness 0.000001)
				)
				(justify left mirror)
			)
		)
		(property "Device Type" "REST0216"
			(at 0.148158 1.3462 270)
			(unlocked yes)
			(layer "B.Fab")
			(hide yes)
			(effects
				(font
					(size 1.27 0.9652)
					(thickness 0.000001)
				)
				(justify left mirror)
			)
		)
		(duplicate_pad_numbers_are_jumpers no)
		(fp_poly
			(pts
				(xy -0.635 1.0668) (xy -0.635 -1.0668) (xy 0.635 -1.0668) (xy 0.635 1.0668)
			)
			(stroke
				(width 0)
				(type default)
			)
			(fill no)
			(layer "B.CrtYd")
		)
		(fp_line
			(start -0.254 -0.508)
			(end -0.254 0.508)
			(stroke
				(width 0.0254)
				(type default)
			)
			(layer "B.Fab")
		)
		(fp_line
			(start -0.254 0.508)
			(end 0.254 0.508)
			(stroke
				(width 0.0254)
				(type default)
			)
			(layer "B.Fab")
		)
		(fp_line
			(start 0.254 -0.508)
			(end -0.254 -0.508)
			(stroke
				(width 0.0254)
				(type default)
			)
			(layer "B.Fab")
		)
		(fp_line
			(start 0.254 0.508)
			(end 0.254 -0.508)
			(stroke
				(width 0.0254)
				(type default)
			)
			(layer "B.Fab")
		)
		(pad "1" smd rect
			(at 0 -0.4191 180)
			(size 0.508 0.5334)
			(layers "B.Cu" "B.Mask" "B.Paste")
			(net "GND")
		)
		(pad "2" smd rect
			(at 0 0.4191 180)
			(size 0.508 0.5334)
			(layers "B.Cu" "B.Mask" "B.Paste")
			(net "11N2146")
		)
		(zone
			(layer "B.Cu")
			(hatch none 0.5)
			(connect_pads
				(clearance 0)
			)
			(min_thickness 0.25)
			(keepout
				(tracks not_allowed)
				(vias allowed)
				(pads allowed)
				(copperpour not_allowed)
				(footprints allowed)
			)
			(placement
				(enabled no)
				(sheetname "")
			)
			(fill
				(thermal_gap 0.5)
				(thermal_bridge_width 0.5)
				(island_removal_mode 0)
			)
			(polygon
				(pts
					(xy 82.9056 41.5544) (xy 82.9056 41.6052) (xy 82.9564 41.6052) (xy 82.9564 41.5544)
				)
			)
		)
	)
	(footprint ""
		(layer "B.Cu")
		(at 81.050994 14.256004)
		(property "Reference" "V2_A-BA2"
			(at 0 0 0)
			(layer "B.SilkS")
			(hide yes)
			(effects
				(font
					(size 1.27 1.27)
				)
				(justify mirror)
			)
		)
		(property "Value" ""
			(at 0 0 0)
			(layer "B.Fab")
			(effects
				(font
					(size 1.27 1.27)
				)
				(justify mirror)
			)
		)
		(duplicate_pad_numbers_are_jumpers no)
		(pad "1" thru_hole circle
			(at 0 0 180)
			(size 0.4572 0.4572)
			(drill 0.20574)
			(layers "*.Cu" "*.Mask")
			(remove_unused_layers no)
			(net "DDR0_32A_BA2")
			(clearance 0.1143)
			(thermal_gap 0.1143)
		)
	)
	(footprint ""
		(layer "B.Cu")
		(at 77.051002 7.498994)
		(property "Reference" "V_A-DQ02"
			(at 0 0 0)
			(layer "B.SilkS")
			(hide yes)
			(effects
				(font
					(size 1.27 1.27)
				)
				(justify mirror)
			)
		)
		(property "Value" ""
			(at 0 0 0)
			(layer "B.Fab")
			(effects
				(font
					(size 1.27 1.27)
				)
				(justify mirror)
			)
		)
		(duplicate_pad_numbers_are_jumpers no)
		(pad "1" thru_hole circle
			(at 0 0 180)
			(size 0.4572 0.4572)
			(drill 0.20574)
			(layers "*.Cu" "*.Mask")
			(remove_unused_layers no)
			(net "DDR0_32A_DQ2")
			(clearance 0.1143)
			(thermal_gap 0.1143)
		)
	)
	(footprint ""
		(layer "B.Cu")
		(at 65.532 3.556)
		(property "Reference" "L1"
			(at 0.762 -1.11633 0)
			(unlocked yes)
			(layer "B.SilkS")
			(effects
				(font
					(size 0.7874 0.5842)
					(thickness 0.127)
				)
				(justify left mirror)
			)
		)
		(property "Value" ""
			(at 0 0 0)
			(layer "B.Fab")
			(effects
				(font
					(size 1.27 1.27)
				)
				(justify mirror)
			)
		)
		(duplicate_pad_numbers_are_jumpers no)
		(fp_rect
			(start -1.7907 0.889)
			(end 1.7907 -0.889)
			(stroke
				(width 0)
				(type default)
			)
			(fill no)
			(layer "B.CrtYd")
		)
		(fp_line
			(start -1.778 -0.762)
			(end -1.778 0.762)
			(stroke
				(width 0.0254)
				(type default)
			)
			(layer "B.Fab")
		)
		(fp_line
			(start -1.778 0.762)
			(end 1.778 0.762)
			(stroke
				(width 0.0254)
				(type default)
			)
			(layer "B.Fab")
		)
		(fp_line
			(start 1.778 -0.762)
			(end -1.778 -0.762)
			(stroke
				(width 0.0254)
				(type default)
			)
			(layer "B.Fab")
		)
		(fp_line
			(start 1.778 0.762)
			(end 1.778 -0.762)
			(stroke
				(width 0.0254)
				(type default)
			)
			(layer "B.Fab")
		)
		(pad "1" smd rect
			(at 0.7493 0 90)
			(size 0.7874 0.8128)
			(layers "B.Cu" "B.Mask" "B.Paste")
			(net "VDD_1.8V")
		)
		(pad "2" smd rect
			(at -0.7493 0 90)
			(size 0.7874 0.8128)
			(layers "B.Cu" "B.Mask" "B.Paste")
			(net "VDDAH_PCIE0")
		)
		(zone
			(layer "B.Cu")
			(hatch none 0.5)
			(connect_pads
				(clearance 0)
			)
			(min_thickness 0.25)
			(keepout
				(tracks not_allowed)
				(vias allowed)
				(pads allowed)
				(copperpour not_allowed)
				(footprints allowed)
			)
			(placement
				(enabled no)
				(sheetname "")
			)
			(fill
				(thermal_gap 0.5)
				(thermal_bridge_width 0.5)
				(island_removal_mode 0)
			)
			(polygon
				(pts
					(xy 65.8114 3.1496) (xy 65.8114 3.9624) (xy 65.2526 3.9624) (xy 65.2526 3.1496)
				)
			)
		)
	)
	(footprint ""
		(layer "B.Cu")
		(at 63.119 36.957 180)
		(property "Reference" "R75"
			(at 0.91567 -1.016 270)
			(unlocked yes)
			(layer "B.SilkS")
			(effects
				(font
					(size 0.7874 0.5842)
					(thickness 0.127)
				)
				(justify left mirror)
			)
		)
		(property "Value" "4.75K"
			(at 0.148158 1.3462 90)
			(unlocked yes)
			(layer "B.Fab")
			(hide yes)
			(effects
				(font
					(size 1.27 0.9652)
					(thickness 0.000001)
				)
				(justify left mirror)
			)
		)
		(property "Device Type" "REST4024"
			(at 0.148158 1.3462 90)
			(unlocked yes)
			(layer "B.Fab")
			(hide yes)
			(effects
				(font
					(size 1.27 0.9652)
					(thickness 0.000001)
				)
				(justify left mirror)
			)
		)
		(duplicate_pad_numbers_are_jumpers no)
		(fp_poly
			(pts
				(xy -0.635 1.0668) (xy -0.635 -1.0668) (xy 0.635 -1.0668) (xy 0.635 1.0668)
			)
			(stroke
				(width 0)
				(type default)
			)
			(fill no)
			(layer "B.CrtYd")
		)
		(fp_line
			(start 0.254 0.508)
			(end 0.254 -0.508)
			(stroke
				(width 0.0254)
				(type default)
			)
			(layer "B.Fab")
		)
		(fp_line
			(start 0.254 -0.508)
			(end -0.254 -0.508)
			(stroke
				(width 0.0254)
				(type default)
			)
			(layer "B.Fab")
		)
		(fp_line
			(start -0.254 0.508)
			(end 0.254 0.508)
			(stroke
				(width 0.0254)
				(type default)
			)
			(layer "B.Fab")
		)
		(fp_line
			(start -0.254 -0.508)
			(end -0.254 0.508)
			(stroke
				(width 0.0254)
				(type default)
			)
			(layer "B.Fab")
		)
		(pad "1" smd rect
			(at 0 -0.4191)
			(size 0.508 0.5334)
			(layers "B.Cu" "B.Mask" "B.Paste")
			(net "CORE_FB_PH1_THERM_L")
		)
		(pad "2" smd rect
			(at 0 0.4191)
			(size 0.508 0.5334)
			(layers "B.Cu" "B.Mask" "B.Paste")
			(net "VDD_3.3V")
		)
		(zone
			(layer "B.Cu")
			(hatch none 0.5)
			(connect_pads
				(clearance 0)
			)
			(min_thickness 0.25)
			(keepout
				(tracks not_allowed)
				(vias allowed)
				(pads allowed)
				(copperpour not_allowed)
				(footprints allowed)
			)
			(placement
				(enabled no)
				(sheetname "")
			)
			(fill
				(thermal_gap 0.5)
				(thermal_bridge_width 0.5)
				(island_removal_mode 0)
			)
			(polygon
				(pts
					(xy 63.1444 36.9824) (xy 63.1444 36.9316) (xy 63.0936 36.9316) (xy 63.0936 36.9824)
				)
			)
		)
	)
	(footprint ""
		(layer "B.Cu")
		(at 22.606 22.352 90)
		(property "Reference" "U7"
			(at -3.81 -2.94767 270)
			(unlocked yes)
			(layer "B.SilkS")
			(effects
				(font
					(size 0.7874 0.5842)
					(thickness 0.127)
				)
				(justify left mirror)
			)
		)
		(property "Value" "*"
			(at 2.0066 1.756842 90)
			(unlocked yes)
			(layer "B.Fab")
			(hide yes)
			(effects
				(font
					(size 1.27 0.9652)
					(thickness 0.000001)
				)
				(justify left mirror)
			)
		)
		(property "Device Type" "PROG0053"
			(at 2.0066 1.756842 90)
			(unlocked yes)
			(layer "B.Fab")
			(hide yes)
			(effects
				(font
					(size 1.27 0.9652)
					(thickness 0.000001)
				)
				(justify left mirror)
			)
		)
		(duplicate_pad_numbers_are_jumpers no)
		(fp_line
			(start 2.286 -2.794)
			(end -2.286 -2.794)
			(stroke
				(width 0.2032)
				(type default)
			)
			(layer "B.SilkS")
		)
		(fp_line
			(start 0.762 -2.794)
			(end 0.762 -1.905)
			(stroke
				(width 0.2032)
				(type default)
			)
			(layer "B.SilkS")
		)
		(fp_line
			(start -2.286 -2.794)
			(end -2.286 -2.54)
			(stroke
				(width 0.2032)
				(type default)
			)
			(layer "B.SilkS")
		)
		(fp_line
			(start 2.286 -2.54)
			(end 2.286 -2.794)
			(stroke
				(width 0.2032)
				(type default)
			)
			(layer "B.SilkS")
		)
		(fp_line
			(start 0.762 -1.905)
			(end -0.762 -1.905)
			(stroke
				(width 0.2032)
				(type default)
			)
			(layer "B.SilkS")
		)
		(fp_line
			(start -0.762 -1.905)
			(end -0.762 -2.794)
			(stroke
				(width 0.2032)
				(type default)
			)
			(layer "B.SilkS")
		)
		(fp_line
			(start 2.286 2.54)
			(end 2.286 2.794)
			(stroke
				(width 0.2032)
				(type default)
			)
			(layer "B.SilkS")
		)
		(fp_line
			(start 2.286 2.794)
			(end -2.286 2.794)
			(stroke
				(width 0.2032)
				(type default)
			)
			(layer "B.SilkS")
		)
		(fp_line
			(start -2.286 2.794)
			(end -2.286 2.54)
			(stroke
				(width 0.2032)
				(type default)
			)
			(layer "B.SilkS")
		)
		(fp_circle
			(center 2.794 -2.794)
			(end 2.794 -2.54)
			(stroke
				(width 0.2032)
				(type default)
			)
			(fill no)
			(layer "B.SilkS")
		)
		(fp_poly
			(pts
				(xy -2.54 3.048) (xy -2.54 2.921) (xy -4.191 2.921) (xy -4.191 -2.921) (xy -2.54 -2.921) (xy -2.54 -3.048)
				(xy 2.54 -3.048) (xy 2.54 -2.921) (xy 4.191 -2.921) (xy 4.191 2.921) (xy 2.54 2.921) (xy 2.54 3.048)
			)
			(stroke
				(width 0)
				(type default)
			)
			(fill no)
			(layer "B.CrtYd")
		)
		(fp_line
			(start 2.0066 -2.5019)
			(end 2.0066 2.5019)
			(stroke
				(width 0.2032)
				(type default)
			)
			(layer "B.Fab")
		)
		(fp_line
			(start -2.0066 -2.5019)
			(end 2.0066 -2.5019)
			(stroke
				(width 0.2032)
				(type default)
			)
			(layer "B.Fab")
		)
		(fp_line
			(start 0.635 -2.4892)
			(end 0.635 -1.7272)
			(stroke
				(width 0.2032)
				(type default)
			)
			(layer "B.Fab")
		)
		(fp_line
			(start 0.635 -1.7272)
			(end -0.635 -1.7272)
			(stroke
				(width 0.2032)
				(type default)
			)
			(layer "B.Fab")
		)
		(fp_line
			(start -0.635 -1.7272)
			(end -0.635 -2.4892)
			(stroke
				(width 0.2032)
				(type default)
			)
			(layer "B.Fab")
		)
		(fp_line
			(start 2.0066 2.5019)
			(end -2.0066 2.5019)
			(stroke
				(width 0.2032)
				(type default)
			)
			(layer "B.Fab")
		)
		(fp_line
			(start -2.0066 2.5019)
			(end -2.0066 -2.5019)
			(stroke
				(width 0.2032)
				(type default)
			)
			(layer "B.Fab")
		)
		(fp_circle
			(center 1.524 -1.905)
			(end 1.524 -1.621028)
			(stroke
				(width 0.2032)
				(type default)
			)
			(fill no)
			(layer "B.Fab")
		)
		(pad "1" smd rect
			(at 2.667 -1.905 270)
			(size 2.032 0.635)
			(layers "B.Cu" "B.Mask" "B.Paste")
			(net "NFP_ARM_SPI_FLASH_SEL")
		)
		(pad "2" smd rect
			(at 2.667 -0.635 270)
			(size 2.032 0.635)
			(layers "B.Cu" "B.Mask" "B.Paste")
			(net "NFP_ARM_SPI_FLASH_MISO")
		)
		(pad "3" smd rect
			(at 2.667 0.635 270)
			(size 2.032 0.635)
			(layers "B.Cu" "B.Mask" "B.Paste")
			(net "NFP_ARM_SPI_FLASH_WP_L")
		)
		(pad "4" smd rect
			(at 2.667 1.905 270)
			(size 2.032 0.635)
			(layers "B.Cu" "B.Mask" "B.Paste")
			(net "GND")
		)
		(pad "5" smd rect
			(at -2.667 1.905 270)
			(size 2.032 0.635)
			(layers "B.Cu" "B.Mask" "B.Paste")
			(net "NFP_ARM_SPI_FLASH_MOSI")
		)
		(pad "6" smd rect
			(at -2.667 0.635 270)
			(size 2.032 0.635)
			(layers "B.Cu" "B.Mask" "B.Paste")
			(net "NFP_ARM_SPI_FLASH_SCK")
		)
		(pad "7" smd rect
			(at -2.667 -0.635 270)
			(size 2.032 0.635)
			(layers "B.Cu" "B.Mask" "B.Paste")
			(net "3N2521")
		)
		(pad "8" smd rect
			(at -2.667 -1.905 270)
			(size 2.032 0.635)
			(layers "B.Cu" "B.Mask" "B.Paste")
			(net "VDD_3.3V")
		)
	)
	(footprint ""
		(layer "B.Cu")
		(at 15.113 32.131)
		(property "Reference" "TP68"
			(at -1.016 -0.73533 0)
			(unlocked yes)
			(layer "B.SilkS")
			(effects
				(font
					(size 0.7874 0.5842)
					(thickness 0.127)
				)
				(justify left mirror)
			)
		)
		(property "Value" "*"
			(at 0.4826 -0.14732 0)
			(unlocked yes)
			(layer "B.Fab")
			(hide yes)
			(effects
				(font
					(size 1.27 0.9652)
					(thickness 0.000001)
				)
				(justify left mirror)
			)
		)
		(property "Device Type" "TP_SMALL"
			(at 0.4826 -0.14732 0)
			(unlocked yes)
			(layer "B.Fab")
			(hide yes)
			(effects
				(font
					(size 1.27 0.9652)
					(thickness 0.000001)
				)
				(justify left mirror)
			)
		)
		(duplicate_pad_numbers_are_jumpers no)
		(fp_line
			(start -0.8636 -0.8636)
			(end 0.8636 -0.8636)
			(stroke
				(width 0.1524)
				(type default)
			)
			(layer "B.SilkS")
		)
		(fp_line
			(start -0.8636 0.8636)
			(end -0.8636 -0.8636)
			(stroke
				(width 0.1524)
				(type default)
			)
			(layer "B.SilkS")
		)
		(fp_line
			(start 0.8636 -0.8636)
			(end 0.8636 0.8636)
			(stroke
				(width 0.1524)
				(type default)
			)
			(layer "B.SilkS")
		)
		(fp_line
			(start 0.8636 0.8636)
			(end -0.8636 0.8636)
			(stroke
				(width 0.1524)
				(type default)
			)
			(layer "B.SilkS")
		)
		(fp_poly
			(pts
				(xy 0.635 -0.635) (xy 0.635 0.635) (xy -0.635 0.635) (xy -0.635 -0.635)
			)
			(stroke
				(width 0)
				(type default)
			)
			(fill no)
			(layer "B.CrtYd")
		)
		(pad "1" smd rect
			(at 0 0 180)
			(size 1.27 1.27)
			(layers "B.Cu" "B.Mask" "B.Paste")
			(net "MAIN_3.3V")
		)
	)
)
